# S9S_MB_2U (Grand Teton) — schematic netlist excerpt (pin names and nets, part order shuffled) for the footprints in the layout excerpt that follows; sources: Cadence DE-HDL packaged netlist, KiCad conversion of 03242023_DA0F0TMBIJ0_F0T_Motherboard_J_brd_V01_OCP.brd

PC583  Q_CAPP  560UF 2.5V 20% OSCON  pkg THLF  page 285 : A = PVCCIN_CPU1 ; B = GND
R4758  Q_RES  0 5% EMPTY  pkg 0402LF  page 164 : A = OCP_V3_2_AUX_PWR_PLD_EN_R ; B = OCP_V3_2_AUX_PWR_EN_R2
C2252  Q_CAP  0.1UF 25V 10% X7R  pkg 0402  page 225 : A = P0V62_CPU0_RST_DDR_VREF ; B = GND

(kicad_pcb
	(version 20260206)
	(generator "pcbnew")
	(generator_version "10.0")
	(general
		(thickness 1.6)
		(legacy_teardrops no)
	)
	(paper "A4")
	(title_block
		(title "03242023_DA0F0TMBIJ0_F0T_Motherboard_J_brd_V01_OCP.brd")
		(comment 1 "Grand Teton / footprints 2377-2379 of 6105")
	)
	(layers
		(0 "F.Cu" signal "TOP")
		(4 "In1.Cu" signal "GND")
		(6 "In2.Cu" signal "IN1")
		(8 "In3.Cu" signal "GND1")
		(10 "In4.Cu" signal "IN2")
		(12 "In5.Cu" signal "GND2")
		(14 "In6.Cu" signal "IN3")
		(16 "In7.Cu" signal "GND3")
		(18 "In8.Cu" signal "VCC")
		(20 "In9.Cu" signal "VCC1")
		(22 "In10.Cu" signal "GND4")
		(24 "In11.Cu" signal "IN4")
		(26 "In12.Cu" signal "GND5")
		(28 "In13.Cu" signal "IN5")
		(30 "In14.Cu" signal "GND6")
		(32 "In15.Cu" signal "IN6")
		(34 "In16.Cu" signal "GND7")
		(2 "B.Cu" signal "BOTTOM")
		(9 "F.Adhes" user "F.Adhesive")
		(11 "B.Adhes" user "B.Adhesive")
		(13 "F.Paste" user "Package Geometry/Pastemask Top")
		(15 "B.Paste" user "Package Geometry/Pastemask Bottom")
		(5 "F.SilkS" user "Ref Des/Silkscreen Top")
		(7 "B.SilkS" user "Ref Des/Silkscreen Bottom")
		(1 "F.Mask" user "Board Geometry/Soldermask Top")
		(3 "B.Mask" user "Board Geometry/Soldermask Bottom")
		(17 "Dwgs.User" user "User.Drawings")
		(19 "Cmts.User" user "User.Comments")
		(21 "Eco1.User" user "User.Eco1")
		(23 "Eco2.User" user "User.Eco2")
		(25 "Edge.Cuts" user "Board Geometry/Outline")
		(27 "Margin" user)
		(31 "F.CrtYd" user "Package Geometry/Place Bound Top")
		(29 "B.CrtYd" user "Package Geometry/Place Bound Bottom")
		(35 "F.Fab" user "Ref Des/Assembly Top")
		(33 "B.Fab" user "Ref Des/Assembly Bottom")
	)
	(footprint ""
		(layer "F.Cu")
		(at 143.895318 -113.463324 180)
		(property "Reference" "R4758"
			(at 0 0 180)
			(layer "F.SilkS")
			(hide yes)
			(effects
				(font
					(size 1.27 1.27)
				)
			)
		)
		(property "Value" ""
			(at 0 0 180)
			(layer "F.Fab")
			(effects
				(font
					(size 1.27 1.27)
				)
			)
		)
		(duplicate_pad_numbers_are_jumpers no)
		(fp_line
			(start 0.7874 0.4064)
			(end -0.7874 0.4064)
			(stroke
				(width 0.1524)
				(type default)
			)
			(layer "F.SilkS")
		)
		(fp_line
			(start 0.7874 -0.4064)
			(end 0.7874 0.4064)
			(stroke
				(width 0.1524)
				(type default)
			)
			(layer "F.SilkS")
		)
		(fp_line
			(start -0.7874 0.4064)
			(end -0.7874 -0.4064)
			(stroke
				(width 0.1524)
				(type default)
			)
			(layer "F.SilkS")
		)
		(fp_line
			(start -0.7874 -0.4064)
			(end 0.7874 -0.4064)
			(stroke
				(width 0.1524)
				(type default)
			)
			(layer "F.SilkS")
		)
		(fp_line
			(start 0.67945 0.3048)
			(end 0.120396 0.3048)
			(stroke
				(width 0.1)
				(type default)
			)
			(layer "F.Fab")
		)
		(fp_line
			(start 0.67945 -0.3048)
			(end 0.67945 0.3048)
			(stroke
				(width 0.1)
				(type default)
			)
			(layer "F.Fab")
		)
		(fp_line
			(start 0.12065 -0.2794)
			(end 0.12065 -0.3048)
			(stroke
				(width 0.1)
				(type default)
			)
			(layer "F.Fab")
		)
		(fp_line
			(start 0.12065 -0.3048)
			(end 0.67945 -0.3048)
			(stroke
				(width 0.1)
				(type default)
			)
			(layer "F.Fab")
		)
		(fp_line
			(start 0.120396 0.3048)
			(end 0.120396 0.2794)
			(stroke
				(width 0.1)
				(type default)
			)
			(layer "F.Fab")
		)
		(fp_line
			(start 0.120396 0.2794)
			(end -0.12065 0.2794)
			(stroke
				(width 0.1)
				(type default)
			)
			(layer "F.Fab")
		)
		(fp_line
			(start -0.12065 0.3048)
			(end -0.67945 0.3048)
			(stroke
				(width 0.1)
				(type default)
			)
			(layer "F.Fab")
		)
		(fp_line
			(start -0.12065 0.2794)
			(end -0.12065 0.3048)
			(stroke
				(width 0.1)
				(type default)
			)
			(layer "F.Fab")
		)
		(fp_line
			(start -0.12065 -0.2794)
			(end 0.12065 -0.2794)
			(stroke
				(width 0.1)
				(type default)
			)
			(layer "F.Fab")
		)
		(fp_line
			(start -0.12065 -0.305054)
			(end -0.12065 -0.2794)
			(stroke
				(width 0.1)
				(type default)
			)
			(layer "F.Fab")
		)
		(fp_line
			(start -0.67945 0.3048)
			(end -0.67945 -0.305054)
			(stroke
				(width 0.1)
				(type default)
			)
			(layer "F.Fab")
		)
		(fp_line
			(start -0.67945 -0.305054)
			(end -0.12065 -0.305054)
			(stroke
				(width 0.1)
				(type default)
			)
			(layer "F.Fab")
		)
		(pad "1" smd circle
			(at -0.40005 0 180)
			(size 0 0)
			(layers "F.Cu" "F.Mask" "F.Paste")
			(net "OCP_V3_2_AUX_PWR_PLD_EN_R")
		)
		(pad "2" smd circle
			(at 0.40005 0 180)
			(size 0 0)
			(layers "F.Cu" "F.Mask" "F.Paste")
			(net "OCP_V3_2_AUX_PWR_EN_R2")
		)
	)
	(footprint ""
		(layer "F.Cu")
		(at 117.098826 -315.66739 90)
		(property "Reference" "PC583"
			(at 0 0 90)
			(layer "F.SilkS")
			(hide yes)
			(effects
				(font
					(size 1.27 1.27)
				)
			)
		)
		(property "Value" ""
			(at 0 0 90)
			(layer "F.Fab")
			(effects
				(font
					(size 1.27 1.27)
				)
			)
		)
		(duplicate_pad_numbers_are_jumpers no)
		(fp_line
			(start 2.750058 0.999998)
			(end -2.750058 0.999998)
			(stroke
				(width 0.1524)
				(type default)
			)
			(layer "F.SilkS")
		)
		(fp_circle
			(center 0 0.999998)
			(end 0 3.750056)
			(stroke
				(width 0.1524)
				(type default)
			)
			(fill no)
			(layer "F.SilkS")
		)
		(fp_poly
			(pts
				(arc
					(start 2.750058 0.999998)
					(mid 0 3.750056)
					(end -2.750058 0.999998)
				)
			)
			(stroke
				(width 0)
				(type default)
			)
			(fill yes)
			(layer "F.SilkS")
		)
		(fp_circle
			(center 0 0.999998)
			(end 0 3.750056)
			(stroke
				(width 0.1)
				(type default)
			)
			(fill no)
			(layer "F.Fab")
		)
		(pad "1" thru_hole rect
			(at 0 0 90)
			(size 1.5748 1.5748)
			(drill 1.0668)
			(layers "*.Cu" "*.Mask")
			(remove_unused_layers no)
			(net "PVCCIN_CPU1")
			(clearance 0)
			(padstack
				(mode front_inner_back)
				(layer "Inner"
					(shape circle)
					(size 1.5748 1.5748)
					(clearance 0)
				)
				(layer "B.Cu"
					(shape rect)
					(size 1.5748 1.5748)
					(clearance 0)
				)
			)
		)
		(pad "2" thru_hole circle
			(at 0 1.999996 90)
			(size 1.5748 1.5748)
			(drill 1.0668)
			(layers "*.Cu" "*.Mask")
			(remove_unused_layers no)
			(net "GND")
			(clearance 0)
		)
	)
	(footprint ""
		(layer "F.Cu")
		(at 114.68608 -122.132598 90)
		(property "Reference" "C2252"
			(at 0 0 90)
			(layer "F.SilkS")
			(hide yes)
			(effects
				(font
					(size 1.27 1.27)
				)
			)
		)
		(property "Value" ""
			(at 0 0 90)
			(layer "F.Fab")
			(effects
				(font
					(size 1.27 1.27)
				)
			)
		)
		(duplicate_pad_numbers_are_jumpers no)
		(fp_line
			(start 0.7874 -0.4064)
			(end 0.7874 0.4064)
			(stroke
				(width 0.1524)
				(type default)
			)
			(layer "F.SilkS")
		)
		(fp_line
			(start -0.7874 -0.4064)
			(end 0.7874 -0.4064)
			(stroke
				(width 0.1524)
				(type default)
			)
			(layer "F.SilkS")
		)
		(fp_line
			(start 0.7874 0.4064)
			(end -0.7874 0.4064)
			(stroke
				(width 0.1524)
				(type default)
			)
			(layer "F.SilkS")
		)
		(fp_line
			(start -0.7874 0.4064)
			(end -0.7874 -0.4064)
			(stroke
				(width 0.1524)
				(type default)
			)
			(layer "F.SilkS")
		)
		(fp_line
			(start -0.12065 -0.305054)
			(end -0.12065 -0.2794)
			(stroke
				(width 0.1)
				(type default)
			)
			(layer "F.Fab")
		)
		(fp_line
			(start -0.67945 -0.305054)
			(end -0.12065 -0.305054)
			(stroke
				(width 0.1)
				(type default)
			)
			(layer "F.Fab")
		)
		(fp_line
			(start 0.67945 -0.3048)
			(end 0.67945 0.3048)
			(stroke
				(width 0.1)
				(type default)
			)
			(layer "F.Fab")
		)
		(fp_line
			(start 0.12065 -0.3048)
			(end 0.67945 -0.3048)
			(stroke
				(width 0.1)
				(type default)
			)
			(layer "F.Fab")
		)
		(fp_line
			(start 0.12065 -0.2794)
			(end 0.12065 -0.3048)
			(stroke
				(width 0.1)
				(type default)
			)
			(layer "F.Fab")
		)
		(fp_line
			(start -0.12065 -0.2794)
			(end 0.12065 -0.2794)
			(stroke
				(width 0.1)
				(type default)
			)
			(layer "F.Fab")
		)
		(fp_line
			(start 0.120396 0.2794)
			(end -0.12065 0.2794)
			(stroke
				(width 0.1)
				(type default)
			)
			(layer "F.Fab")
		)
		(fp_line
			(start -0.12065 0.2794)
			(end -0.12065 0.3048)
			(stroke
				(width 0.1)
				(type default)
			)
			(layer "F.Fab")
		)
		(fp_line
			(start 0.67945 0.3048)
			(end 0.120396 0.3048)
			(stroke
				(width 0.1)
				(type default)
			)
			(layer "F.Fab")
		)
		(fp_line
			(start 0.120396 0.3048)
			(end 0.120396 0.2794)
			(stroke
				(width 0.1)
				(type default)
			)
			(layer "F.Fab")
		)
		(fp_line
			(start -0.12065 0.3048)
			(end -0.67945 0.3048)
			(stroke
				(width 0.1)
				(type default)
			)
			(layer "F.Fab")
		)
		(fp_line
			(start -0.67945 0.3048)
			(end -0.67945 -0.305054)
			(stroke
				(width 0.1)
				(type default)
			)
			(layer "F.Fab")
		)
		(pad "1" smd circle
			(at -0.40005 0 90)
			(size 0 0)
			(layers "F.Cu" "F.Mask" "F.Paste")
			(net "P0V62_CPU0_RST_DDR_VREF")
		)
		(pad "2" smd circle
			(at 0.40005 0 90)
			(size 0 0)
			(layers "F.Cu" "F.Mask" "F.Paste")
			(net "GND")
		)
	)
)
